# T6G (Grand Teton) — schematic netlist excerpt (pin names and nets, part order shuffled) for the footprints in the layout excerpt that follows; sources: Cadence DE-HDL packaged netlist, KiCad conversion of 04192023_DAF0TMB3IC0_F0TG_MB_C_brd_V02_OCP.brd

R1110  Q_RES  0 5% CHIP  pkg 0201LF  page 309 : A = SMB_RT_CPU0_P3_R_SDA ; B = SMB_RT_CPU0_P3_R2_SDA
PR271  Q_RES  2.2 1% CHIP  pkg 0402LF  page 220 : A = PVDDCR_CPU1_P1_PVCC ; B = PVDDCR_CPU1_P1_VCC5
PC160  Q_CAPP  470UF 2.5V 20% EMPTY  pkg SMLF  page 205 : A = PVDDIO_P0 ; B = GND

(kicad_pcb
	(version 20260206)
	(generator "pcbnew")
	(generator_version "10.0")
	(general
		(thickness 1.6)
		(legacy_teardrops no)
	)
	(paper "A4")
	(title_block
		(title "04192023_DAF0TMB3IC0_F0TG_MB_C_brd_V02_OCP.brd")
		(comment 1 "Grand Teton / footprints 7432-7434 of 8354")
	)
	(layers
		(0 "F.Cu" signal "TOP")
		(4 "In1.Cu" signal "GND")
		(6 "In2.Cu" signal "IN1")
		(8 "In3.Cu" signal "GND1")
		(10 "In4.Cu" signal "IN2")
		(12 "In5.Cu" signal "GND2")
		(14 "In6.Cu" signal "IN3")
		(16 "In7.Cu" signal "GND3")
		(18 "In8.Cu" signal "VCC")
		(20 "In9.Cu" signal "VCC1")
		(22 "In10.Cu" signal "GND4")
		(24 "In11.Cu" signal "IN4")
		(26 "In12.Cu" signal "GND5")
		(28 "In13.Cu" signal "IN5")
		(30 "In14.Cu" signal "GND6")
		(32 "In15.Cu" signal "IN6")
		(34 "In16.Cu" signal "GND7")
		(2 "B.Cu" signal "BOTTOM")
		(9 "F.Adhes" user "F.Adhesive")
		(11 "B.Adhes" user "B.Adhesive")
		(13 "F.Paste" user "Package Geometry/Pastemask Top")
		(15 "B.Paste" user "Package Geometry/Pastemask Bottom")
		(5 "F.SilkS" user "Ref Des/Silkscreen Top")
		(7 "B.SilkS" user "Ref Des/Silkscreen Bottom")
		(1 "F.Mask" user "Board Geometry/Soldermask Top")
		(3 "B.Mask" user "Board Geometry/Soldermask Bottom")
		(17 "Dwgs.User" user "User.Drawings")
		(19 "Cmts.User" user "User.Comments")
		(21 "Eco1.User" user "User.Eco1")
		(23 "Eco2.User" user "User.Eco2")
		(25 "Edge.Cuts" user "Board Geometry/Outline")
		(27 "Margin" user)
		(31 "F.CrtYd" user "Package Geometry/Place Bound Top")
		(29 "B.CrtYd" user "Package Geometry/Place Bound Bottom")
		(35 "F.Fab" user "Ref Des/Assembly Top")
		(33 "B.Fab" user "Ref Des/Assembly Bottom")
	)
	(footprint ""
		(layer "B.Cu")
		(at 93.142562 -336.088482 -90)
		(property "Reference" "PR271"
			(at 0 0 90)
			(layer "B.SilkS")
			(hide yes)
			(effects
				(font
					(size 1.27 1.27)
				)
				(justify mirror)
			)
		)
		(property "Value" ""
			(at 0 0 90)
			(layer "B.Fab")
			(effects
				(font
					(size 1.27 1.27)
				)
				(justify mirror)
			)
		)
		(duplicate_pad_numbers_are_jumpers no)
		(fp_line
			(start -0.7874 0.4064)
			(end 0.7874 0.4064)
			(stroke
				(width 0.1524)
				(type default)
			)
			(layer "B.SilkS")
		)
		(fp_line
			(start 0.7874 0.4064)
			(end 0.7874 -0.4064)
			(stroke
				(width 0.1524)
				(type default)
			)
			(layer "B.SilkS")
		)
		(fp_line
			(start -0.7874 -0.4064)
			(end -0.7874 0.4064)
			(stroke
				(width 0.1524)
				(type default)
			)
			(layer "B.SilkS")
		)
		(fp_line
			(start 0.7874 -0.4064)
			(end -0.7874 -0.4064)
			(stroke
				(width 0.1524)
				(type default)
			)
			(layer "B.SilkS")
		)
		(fp_line
			(start -0.67945 0.3048)
			(end -0.120396 0.3048)
			(stroke
				(width 0.1)
				(type default)
			)
			(layer "B.Fab")
		)
		(fp_line
			(start -0.120396 0.3048)
			(end -0.120396 0.2794)
			(stroke
				(width 0.1)
				(type default)
			)
			(layer "B.Fab")
		)
		(fp_line
			(start 0.12065 0.3048)
			(end 0.67945 0.3048)
			(stroke
				(width 0.1)
				(type default)
			)
			(layer "B.Fab")
		)
		(fp_line
			(start 0.67945 0.3048)
			(end 0.67945 -0.305054)
			(stroke
				(width 0.1)
				(type default)
			)
			(layer "B.Fab")
		)
		(fp_line
			(start -0.120396 0.2794)
			(end 0.12065 0.2794)
			(stroke
				(width 0.1)
				(type default)
			)
			(layer "B.Fab")
		)
		(fp_line
			(start 0.12065 0.2794)
			(end 0.12065 0.3048)
			(stroke
				(width 0.1)
				(type default)
			)
			(layer "B.Fab")
		)
		(fp_line
			(start -0.12065 -0.2794)
			(end -0.12065 -0.3048)
			(stroke
				(width 0.1)
				(type default)
			)
			(layer "B.Fab")
		)
		(fp_line
			(start 0.12065 -0.2794)
			(end -0.12065 -0.2794)
			(stroke
				(width 0.1)
				(type default)
			)
			(layer "B.Fab")
		)
		(fp_line
			(start -0.67945 -0.3048)
			(end -0.67945 0.3048)
			(stroke
				(width 0.1)
				(type default)
			)
			(layer "B.Fab")
		)
		(fp_line
			(start -0.12065 -0.3048)
			(end -0.67945 -0.3048)
			(stroke
				(width 0.1)
				(type default)
			)
			(layer "B.Fab")
		)
		(fp_line
			(start 0.12065 -0.305054)
			(end 0.12065 -0.2794)
			(stroke
				(width 0.1)
				(type default)
			)
			(layer "B.Fab")
		)
		(fp_line
			(start 0.67945 -0.305054)
			(end 0.12065 -0.305054)
			(stroke
				(width 0.1)
				(type default)
			)
			(layer "B.Fab")
		)
		(pad "1" smd circle
			(at 0.40005 0 90)
			(size 0 0)
			(layers "B.Cu" "B.Mask" "B.Paste")
			(net "PVDDCR_CPU1_P1_PVCC")
		)
		(pad "2" smd circle
			(at -0.40005 0 90)
			(size 0 0)
			(layers "B.Cu" "B.Mask" "B.Paste")
			(net "PVDDCR_CPU1_P1_VCC5")
		)
	)
	(footprint ""
		(layer "B.Cu")
		(at 275.217128 -339.860128 -90)
		(property "Reference" "PC160"
			(at 9.447276 -0.827786 270)
			(unlocked yes)
			(layer "B.SilkS")
			(effects
				(font
					(size 0.7874 0.5842)
					(thickness 0.1524)
				)
				(justify left mirror)
			)
		)
		(property "Value" ""
			(at 0 0 90)
			(layer "B.Fab")
			(effects
				(font
					(size 1.27 1.27)
				)
				(justify mirror)
			)
		)
		(duplicate_pad_numbers_are_jumpers no)
		(fp_line
			(start -4.533392 2.249932)
			(end 4.533392 2.249932)
			(stroke
				(width 0.1524)
				(type default)
			)
			(layer "B.SilkS")
		)
		(fp_line
			(start 4.533392 2.249932)
			(end 4.533392 -2.249932)
			(stroke
				(width 0.1524)
				(type default)
			)
			(layer "B.SilkS")
		)
		(fp_line
			(start -4.533392 -2.249932)
			(end -4.533392 2.249932)
			(stroke
				(width 0.1524)
				(type default)
			)
			(layer "B.SilkS")
		)
		(fp_line
			(start 4.533392 -2.249932)
			(end -4.533392 -2.249932)
			(stroke
				(width 0.1524)
				(type default)
			)
			(layer "B.SilkS")
		)
		(fp_rect
			(start 5.39242 2.326132)
			(end 4.533392 -2.326132)
			(stroke
				(width 0)
				(type default)
			)
			(fill yes)
			(layer "B.SilkS")
		)
		(fp_line
			(start -3.750056 2.249932)
			(end 3.750056 2.249932)
			(stroke
				(width 0.1)
				(type default)
			)
			(layer "B.Fab")
		)
		(fp_line
			(start 3.750056 2.249932)
			(end 3.750056 -2.249932)
			(stroke
				(width 0.1)
				(type default)
			)
			(layer "B.Fab")
		)
		(fp_line
			(start -3.750056 -2.249932)
			(end -3.750056 2.249932)
			(stroke
				(width 0.1)
				(type default)
			)
			(layer "B.Fab")
		)
		(fp_line
			(start 3.750056 -2.249932)
			(end -3.750056 -2.249932)
			(stroke
				(width 0.1)
				(type default)
			)
			(layer "B.Fab")
		)
		(fp_text user "+"
			(at 6.322314 0.786384 180)
			(unlocked yes)
			(layer "B.SilkS")
			(effects
				(font
					(size 1.905 1.4224)
					(thickness 0.1524)
				)
				(justify left mirror)
			)
		)
		(fp_text user "-"
			(at -4.8514 -0.14605 270)
			(unlocked yes)
			(layer "B.SilkS")
			(effects
				(font
					(size 1.905 1.4224)
					(thickness 0.1524)
				)
				(justify left mirror)
			)
		)
		(fp_text user "+"
			(at 6.322314 0.786384 180)
			(unlocked yes)
			(layer "B.Fab")
			(effects
				(font
					(size 1.905 1.4224)
					(thickness 0.1524)
				)
				(justify left mirror)
			)
		)
		(fp_text user "-"
			(at -4.8514 -0.14605 270)
			(unlocked yes)
			(layer "B.Fab")
			(effects
				(font
					(size 1.905 1.4224)
					(thickness 0.1524)
				)
				(justify left mirror)
			)
		)
		(pad "1" smd rect
			(at 3.199892 0 90)
			(size 2.413 2.8194)
			(layers "B.Cu" "B.Mask" "B.Paste")
			(net "PVDDIO_P0")
		)
		(pad "2" smd rect
			(at -3.199892 0 90)
			(size 2.413 2.8194)
			(layers "B.Cu" "B.Mask" "B.Paste")
			(net "GND")
		)
	)
	(footprint ""
		(layer "B.Cu")
		(at 233.172 -337.312 180)
		(property "Reference" "R1110"
			(at 0 0 0)
			(layer "B.SilkS")
			(hide yes)
			(effects
				(font
					(size 1.27 1.27)
				)
				(justify mirror)
			)
		)
		(property "Value" ""
			(at 0 0 0)
			(layer "B.Fab")
			(effects
				(font
					(size 1.27 1.27)
				)
				(justify mirror)
			)
		)
		(duplicate_pad_numbers_are_jumpers no)
		(fp_line
			(start 0.32512 0.175006)
			(end 0.32512 -0.175006)
			(stroke
				(width 0.1)
				(type default)
			)
			(layer "B.Fab")
		)
		(fp_line
			(start 0.32512 -0.175006)
			(end -0.32512 -0.175006)
			(stroke
				(width 0.1)
				(type default)
			)
			(layer "B.Fab")
		)
		(fp_line
			(start -0.32512 0.175006)
			(end 0.32512 0.175006)
			(stroke
				(width 0.1)
				(type default)
			)
			(layer "B.Fab")
		)
		(fp_line
			(start -0.32512 -0.175006)
			(end -0.32512 0.175006)
			(stroke
				(width 0.1)
				(type default)
			)
			(layer "B.Fab")
		)
		(pad "1" smd rect
			(at 0.2667 0)
			(size 0.3048 0.381)
			(layers "B.Cu" "B.Mask" "B.Paste")
			(net "SMB_RT_CPU0_P3_R_SDA")
		)
		(pad "2" smd rect
			(at -0.2667 0 180)
			(size 0.3048 0.381)
			(layers "B.Cu" "B.Mask" "B.Paste")
			(net "SMB_RT_CPU0_P3_R2_SDA")
		)
	)
)
